(kicad_pcb
	(version 20221018)
	(generator pcbnew)
	(general
    (thickness 1.518)
  )
	(paper "A4")
	(title_block
    (title "Kria K26 Devboard")
    (date "2024-03-26")
    (rev "1.2.5")
    (comment 1 "www.antmicro.com")
    (comment 2 "Antmicro Ltd.")
		(comment 9 "footprints 49-55 of 660")
	)
	(layers
    (0 "F.Cu" mixed)
    (1 "In1.Cu" power)
    (2 "In2.Cu" mixed)
    (3 "In3.Cu" power)
    (4 "In4.Cu" mixed)
    (5 "In5.Cu" power)
    (6 "In6.Cu" mixed)
    (31 "B.Cu" power)
    (32 "B.Adhes" user "B.Adhesive")
    (33 "F.Adhes" user "F.Adhesive")
    (34 "B.Paste" user)
    (35 "F.Paste" user)
    (36 "B.SilkS" user "B.Silkscreen")
    (37 "F.SilkS" user "F.Silkscreen")
    (38 "B.Mask" user)
    (39 "F.Mask" user)
    (40 "Dwgs.User" user "User.Drawings")
    (41 "Cmts.User" user "User.Comments")
    (42 "Eco1.User" user "User.Eco1")
    (43 "Eco2.User" user "User.Eco2")
    (44 "Edge.Cuts" user)
    (45 "Margin" user)
    (46 "B.CrtYd" user "B.Courtyard")
    (47 "F.CrtYd" user "F.Courtyard")
    (48 "B.Fab" user)
    (49 "F.Fab" user)
  )
	(footprint "kria-k26-devboard-footprints:USB-A_Receptacle_Amphenol_GSB3112311HR" (layer "F.Cu")
    (at 113.9 65.73 180)
    (descr "Ethernet Amphenol")
    (tags "Ethernet Amphenol")
    (property "Author" "Antmicro")
    (property "License" "Apache-2.0")
    (property "MPN" "GSB3112311HR")
    (property "Manufacturer" "Amphenol")
    (property "Sheetfile" "usb.kicad_sch")
    (property "Sheetname" "USB")
    (property "ki_description" "USB-A (USB TYPE-A) USB 3.2 Gen 1 (USB 3.1 Gen 1, Superspeed (USB 3.0)) Receptacle Connector 5 Position Through Hole, Right Angle")
    (property "ki_keywords" "USB, CONNECTOR, THT, HORIZONTAL")
    (attr through_hole)
    (fp_text reference "U29" (at 7.86 -6.95) (layer "F.SilkS")
        (effects (font (size 0.7 0.7) (thickness 0.15)) (justify right bottom))
    )
    (fp_text value "USB-A_Amphenol_GSB3112311HR" (at 0 14.8) (layer "F.Fab") hide
        (effects (font (size 0.7 0.7) (thickness 0.15)) (justify right bottom))
    )
    (fp_text user "${REFERENCE}" (at -4.6 16.3) (layer "F.Fab") hide
        (effects (font (size 0.7 0.7) (thickness 0.15)) (justify right bottom))
    )
    (fp_text user "License: Apache-2.0" (at -4.6 18.7) (layer "F.Fab") hide
        (effects (font (size 0.7 0.7) (thickness 0.15)) (justify right bottom))
    )
    (fp_text user "Author: Antmicro" (at -4.6 17.501) (layer "F.Fab") hide
        (effects (font (size 0.7 0.7) (thickness 0.15)) (justify right bottom))
    )
    (fp_rect (start -4.6 13.711) (end 11.7 -6.6)
      (stroke (width 0.05) (type solid)) (fill none) (layer "F.CrtYd"))
    (pad "1" thru_hole circle (at 0 0 270) (size 1.1 1.1) (drill 0.7) (layers "*.Cu" "*.Mask")
      (net 86 "/USB/USB3_VBUS") (pinfunction "VBUS") (pintype "passive"))
    (pad "2" thru_hole circle (at 2.499 0 270) (size 1.1 1.1) (drill 0.7) (layers "*.Cu" "*.Mask")
      (net 290 "/USB/USB3_TVS_N") (pinfunction "D-") (pintype "bidirectional"))
    (pad "3" thru_hole circle (at 4.498 0 270) (size 1.1 1.1) (drill 0.7) (layers "*.Cu" "*.Mask")
      (net 291 "/USB/USB3_TVS_P") (pinfunction "D+") (pintype "bidirectional"))
    (pad "4" thru_hole circle (at 6.999 0 270) (size 1.1 1.1) (drill 0.7) (layers "*.Cu" "*.Mask")
      (net 1 "GND") (pinfunction "GND") (pintype "power_in"))
    (pad "5" thru_hole circle (at 7.499 -1.499 270) (size 1.1 1.1) (drill 0.7) (layers "*.Cu" "*.Mask")
      (net 79 "/USB/USB3_RX_N") (pinfunction "SSRX-") (pintype "bidirectional"))
    (pad "6" thru_hole circle (at 5.499 -1.499 270) (size 1.1 1.1) (drill 0.7) (layers "*.Cu" "*.Mask")
      (net 80 "/USB/USB3_RX_P") (pinfunction "SSRX+") (pintype "bidirectional"))
    (pad "7" thru_hole circle (at 3.499 -1.499 270) (size 1.1 1.1) (drill 0.7) (layers "*.Cu" "*.Mask")
      (net 1 "GND") (pinfunction "GND_DRAIN") (pintype "power_in"))
    (pad "8" thru_hole circle (at 1.499 -1.499 270) (size 1.1 1.1) (drill 0.7) (layers "*.Cu" "*.Mask")
      (net 282 "/USB/USB3_TX_C_N") (pinfunction "SSTX-") (pintype "bidirectional"))
    (pad "9" thru_hole circle (at -0.5 -1.499 270) (size 1.1 1.1) (drill 0.7) (layers "*.Cu" "*.Mask")
      (net 283 "/USB/USB3_TX_C_P") (pinfunction "SSTX+") (pintype "bidirectional"))
    (pad "10" thru_hole circle (at 0 -3.2 270) (size 1.1 1.1) (drill 0.7) (layers "*.Cu" "*.Mask")
      (net 87 "/USB/USB4_VBUS") (pinfunction "VBUS") (pintype "power_in"))
    (pad "11" thru_hole circle (at 2.499 -3.2 270) (size 1.1 1.1) (drill 0.7) (layers "*.Cu" "*.Mask")
      (net 292 "/USB/USB4_TVS_N") (pinfunction "D-") (pintype "bidirectional"))
    (pad "12" thru_hole circle (at 4.498 -3.2 270) (size 1.1 1.1) (drill 0.7) (layers "*.Cu" "*.Mask")
      (net 293 "/USB/USB4_TVS_P") (pinfunction "D+") (pintype "bidirectional"))
    (pad "13" thru_hole circle (at 6.999 -3.2 270) (size 1.1 1.1) (drill 0.7) (layers "*.Cu" "*.Mask")
      (net 1 "GND") (pinfunction "GND") (pintype "power_in"))
    (pad "14" thru_hole circle (at 7.499 -4.7 270) (size 1.1 1.1) (drill 0.7) (layers "*.Cu" "*.Mask")
      (net 73 "/USB/USB4_RX_N") (pinfunction "SSRX-") (pintype "bidirectional"))
    (pad "15" thru_hole circle (at 5.499 -4.7 270) (size 1.1 1.1) (drill 0.7) (layers "*.Cu" "*.Mask")
      (net 74 "/USB/USB4_RX_P") (pinfunction "SSRX+") (pintype "bidirectional"))
    (pad "16" thru_hole circle (at 3.499 -4.7 270) (size 1.1 1.1) (drill 0.7) (layers "*.Cu" "*.Mask")
      (net 1 "GND") (pinfunction "GND_DRAIN") (pintype "power_in"))
    (pad "17" thru_hole circle (at 1.499 -4.7 270) (size 1.1 1.1) (drill 0.7) (layers "*.Cu" "*.Mask")
      (net 284 "/USB/USB4_TX_C_N") (pinfunction "SSTX-") (pintype "bidirectional"))
    (pad "18" thru_hole circle (at -0.5 -4.7 270) (size 1.1 1.1) (drill 0.7) (layers "*.Cu" "*.Mask")
      (net 285 "/USB/USB4_TX_C_P") (pinfunction "SSTX+") (pintype "bidirectional"))
    (pad "SH" thru_hole circle (at -3.072 -3.68 270) (size 2.9 2.9) (drill 2.3) (layers "*.Cu" "*.Mask")
      (net 319 "SH_UP") (pinfunction "SHIELD") (pintype "passive"))
    (pad "SH" thru_hole circle (at -3.072 2 270) (size 2.9 2.9) (drill 2.3) (layers "*.Cu" "*.Mask")
      (net 319 "SH_UP") (pinfunction "SHIELD") (pintype "passive"))
    (pad "SH" thru_hole circle (at 10.07 -3.68 270) (size 2.9 2.9) (drill 2.3) (layers "*.Cu" "*.Mask")
      (net 319 "SH_UP") (pinfunction "SHIELD") (pintype "passive"))
    (pad "SH" thru_hole circle (at 10.169 2 270) (size 2.9 2.9) (drill 2.3) (layers "*.Cu" "*.Mask")
      (net 319 "SH_UP") (pinfunction "SHIELD") (pintype "passive"))
  )
	(footprint "kria-k26-devboard-footprints:C_1206_3216Metric" (layer "F.Cu")
    (at 187.385 116.45)
    (descr "Capacitor SMD 1206")
    (tags "capacitor SMD 1206")
    (property "Author" "Antmicro")
    (property "Dielectric" "")
    (property "License" "Apache-2.0")
    (property "MPN" "C3216X5R1C476M160AB")
    (property "Manufacturer" "TDK")
    (property "Sheetfile" "PoE.kicad_sch")
    (property "Sheetname" "PoE")
    (property "Val" "47u/16V")
    (property "Voltage" "")
    (property "ki_description" " ")
    (attr smd)
    (fp_text reference "C180" (at 0.915 -1.93) (layer "F.SilkS")
        (effects (font (size 0.7 0.7) (thickness 0.15)) (justify left bottom))
    )
    (fp_text value "C_47u_16V_1206" (at 0 2.1) (layer "F.Fab") hide
        (effects (font (size 0.7 0.7) (thickness 0.15)) (justify left bottom))
    )
    (fp_text user "License: Apache-2.0" (at -2.8 6.6) (layer "F.Fab") hide
        (effects (font (size 0.7 0.7) (thickness 0.15)) (justify left bottom))
    )
    (fp_text user "${REFERENCE}" (at -2.8 4.6) (layer "F.Fab") hide
        (effects (font (size 0.7 0.7) (thickness 0.15)) (justify left bottom))
    )
    (fp_text user "Author: Antmicro" (at -2.8 5.6) (layer "F.Fab") hide
        (effects (font (size 0.7 0.7) (thickness 0.15)) (justify left bottom))
    )
    (fp_line (start -2.625 -0.3) (end -2.625 0.3)
      (stroke (width 0.15) (type solid)) (layer "F.SilkS"))
    (fp_line (start 0.5 -0.9) (end -0.5 -0.9)
      (stroke (width 0.15) (type solid)) (layer "F.SilkS"))
    (fp_line (start 0.5 0.9) (end -0.5 0.9)
      (stroke (width 0.15) (type solid)) (layer "F.SilkS"))
    (fp_line (start 2.625 -0.3) (end 2.625 0.3)
      (stroke (width 0.15) (type solid)) (layer "F.SilkS"))
    (fp_rect (start -2.8 -1.15) (end 2.8 1.15)
      (stroke (width 0.05) (type solid)) (fill none) (layer "F.CrtYd"))
    (fp_rect (start -1.6 -0.8) (end 1.6 0.8)
      (stroke (width 0.15) (type solid)) (fill none) (layer "F.Fab"))
    (pad "1" smd rect (at -1.8 0) (size 1.5 1.8) (layers "F.Cu" "F.Paste" "F.Mask")
      (net 13 "/Power Supply/PoE/POE_12V") (pintype "passive"))
    (pad "2" smd rect (at 1.8 0) (size 1.5 1.8) (layers "F.Cu" "F.Paste" "F.Mask")
      (net 1 "GND") (pintype "passive"))
  )
	(footprint "kria-k26-devboard-footprints:R_0402_1005Metric" (layer "F.Cu")
    (at 177.625 130.6)
    (descr "Resistor SMD 0402")
    (tags "resistor SMD 0402")
    (property "Author" "Antmicro")
    (property "License" "Apache-2.0")
    (property "MPN" "CR0402-FX-1002GLF")
    (property "Manufacturer" "Bourns")
    (property "Sheetfile" "dc-dc-conventers.kicad_sch")
    (property "Sheetname" "DC/DC conventers")
    (property "Tolerance" "1%")
    (property "Val" "10k")
    (property "ki_description" "10k resistor in 0402 package with 1% tolerance")
    (attr smd)
    (fp_text reference "R145" (at -0.085 -0.43) (layer "F.SilkS")
        (effects (font (size 0.7 0.7) (thickness 0.15)) (justify left bottom))
    )
    (fp_text value "R_10k_0402" (at 0 1.4) (layer "F.Fab") hide
        (effects (font (size 0.7 0.7) (thickness 0.15)) (justify left bottom))
    )
    (fp_text user "License: Apache-2.0" (at -0.95 5.169) (layer "F.Fab") hide
        (effects (font (size 0.7 0.7) (thickness 0.15)) (justify left bottom))
    )
    (fp_text user "Author: Antmicro" (at -0.95 4.169) (layer "F.Fab") hide
        (effects (font (size 0.7 0.7) (thickness 0.15)) (justify left bottom))
    )
    (fp_text user "${REFERENCE}" (at -0.95 3.168) (layer "F.Fab") hide
        (effects (font (size 0.7 0.7) (thickness 0.15)) (justify left bottom))
    )
    (fp_rect (start -0.93 -0.47) (end 0.93 0.47)
      (stroke (width 0.05) (type solid)) (fill none) (layer "F.CrtYd"))
    (fp_rect (start -0.5 -0.25) (end 0.5 0.25)
      (stroke (width 0.15) (type solid)) (fill none) (layer "F.Fab"))
    (pad "1" smd roundrect (at -0.485 0) (size 0.59 0.64) (layers "F.Cu" "F.Paste" "F.Mask") (roundrect_rratio 0.25)
      (net 693 "Net-(U54-FB)") (pintype "passive"))
    (pad "2" smd roundrect (at 0.485 0) (size 0.59 0.64) (layers "F.Cu" "F.Paste" "F.Mask") (roundrect_rratio 0.25)
      (net 1 "GND") (pintype "passive"))
  )
	(footprint "kria-k26-devboard-footprints:C_0603_1608Metric" (layer "F.Cu")
    (at 182.28 135.925 -90)
    (descr "Capacitor SMD 0603")
    (tags "capacitor 0603")
    (property "Author" "Antmicro")
    (property "Dielectric" "")
    (property "License" "Apache-2.0")
    (property "MPN" "GRM188R60J226MEA0D")
    (property "Manufacturer" "Murata")
    (property "Sheetfile" "dc-dc-conventers.kicad_sch")
    (property "Sheetname" "DC/DC conventers")
    (property "Val" "22u")
    (property "Voltage" "")
    (property "ki_description" " ")
    (attr smd)
    (fp_text reference "C225" (at -1.165 -0.88 -90) (layer "F.SilkS")
        (effects (font (size 0.7 0.7) (thickness 0.15)) (justify left bottom))
    )
    (fp_text value "C_22u_0603" (at 0 1.6 -90) (layer "F.Fab") hide
        (effects (font (size 0.7 0.7) (thickness 0.15)) (justify left bottom))
    )
    (fp_text user "Author: Antmicro" (at -1.682 4.894 -90) (layer "F.Fab") hide
        (effects (font (size 0.7 0.7) (thickness 0.15)) (justify left bottom))
    )
    (fp_text user "${REFERENCE}" (at -1.682 3.895 -90) (layer "F.Fab") hide
        (effects (font (size 0.7 0.7) (thickness 0.15)) (justify left bottom))
    )
    (fp_text user "License: Apache-2.0" (at -1.682 5.895 -90) (layer "F.Fab") hide
        (effects (font (size 0.7 0.7) (thickness 0.15)) (justify left bottom))
    )
    (fp_line (start -0.3 -0.3) (end 0.3 -0.3)
      (stroke (width 0.15) (type solid)) (layer "F.SilkS"))
    (fp_line (start -0.3 0.3) (end 0.3 0.3)
      (stroke (width 0.15) (type solid)) (layer "F.SilkS"))
    (fp_rect (start -1.24 -0.7) (end 1.24 0.7)
      (stroke (width 0.05) (type solid)) (fill none) (layer "F.CrtYd"))
    (fp_rect (start -0.8 -0.4) (end 0.8 0.4)
      (stroke (width 0.15) (type solid)) (fill none) (layer "F.Fab"))
    (pad "1" smd roundrect (at -0.7 0 270) (size 0.6 0.8) (layers "F.Cu" "F.Paste" "F.Mask") (roundrect_rratio 0.2)
      (net 1 "GND") (pintype "passive"))
    (pad "2" smd roundrect (at 0.7 0 270) (size 0.6 0.8) (layers "F.Cu" "F.Paste" "F.Mask") (roundrect_rratio 0.2)
      (net 770 "/Power Supply/DC/DC conventers/PL_3V3_OUT") (pintype "passive"))
  )
	(footprint "kria-k26-devboard-footprints:C_1206_3216Metric" (layer "F.Cu")
    (at 187.399999 118.8)
    (descr "Capacitor SMD 1206")
    (tags "capacitor SMD 1206")
    (property "Author" "Antmicro")
    (property "Dielectric" "")
    (property "License" "Apache-2.0")
    (property "MPN" "C3216X5R1C476M160AB")
    (property "Manufacturer" "TDK")
    (property "Sheetfile" "PoE.kicad_sch")
    (property "Sheetname" "PoE")
    (property "Val" "47u/16V")
    (property "Voltage" "")
    (property "ki_description" " ")
    (attr smd)
    (fp_text reference "C181" (at 0.910001 -3.4) (layer "F.SilkS")
        (effects (font (size 0.7 0.7) (thickness 0.15)) (justify left bottom))
    )
    (fp_text value "C_47u_16V_1206" (at 0 2.1) (layer "F.Fab") hide
        (effects (font (size 0.7 0.7) (thickness 0.15)) (justify left bottom))
    )
    (fp_text user "${REFERENCE}" (at -2.8 4.6) (layer "F.Fab") hide
        (effects (font (size 0.7 0.7) (thickness 0.15)) (justify left bottom))
    )
    (fp_text user "License: Apache-2.0" (at -2.8 6.6) (layer "F.Fab") hide
        (effects (font (size 0.7 0.7) (thickness 0.15)) (justify left bottom))
    )
    (fp_text user "Author: Antmicro" (at -2.8 5.6) (layer "F.Fab") hide
        (effects (font (size 0.7 0.7) (thickness 0.15)) (justify left bottom))
    )
    (fp_line (start -2.625 -0.3) (end -2.625 0.3)
      (stroke (width 0.15) (type solid)) (layer "F.SilkS"))
    (fp_line (start 0.5 -0.9) (end -0.5 -0.9)
      (stroke (width 0.15) (type solid)) (layer "F.SilkS"))
    (fp_line (start 0.5 0.9) (end -0.5 0.9)
      (stroke (width 0.15) (type solid)) (layer "F.SilkS"))
    (fp_line (start 2.625 -0.3) (end 2.625 0.3)
      (stroke (width 0.15) (type solid)) (layer "F.SilkS"))
    (fp_rect (start -2.8 -1.15) (end 2.8 1.15)
      (stroke (width 0.05) (type solid)) (fill none) (layer "F.CrtYd"))
    (fp_rect (start -1.6 -0.8) (end 1.6 0.8)
      (stroke (width 0.15) (type solid)) (fill none) (layer "F.Fab"))
    (pad "1" smd rect (at -1.8 0) (size 1.5 1.8) (layers "F.Cu" "F.Paste" "F.Mask")
      (net 13 "/Power Supply/PoE/POE_12V") (pintype "passive"))
    (pad "2" smd rect (at 1.8 0) (size 1.5 1.8) (layers "F.Cu" "F.Paste" "F.Mask")
      (net 1 "GND") (pintype "passive"))
  )
	(footprint "kria-k26-devboard-footprints:C_0603_1608Metric" (layer "F.Cu")
    (at 180.86 135.92 -90)
    (descr "Capacitor SMD 0603")
    (tags "capacitor 0603")
    (property "Author" "Antmicro")
    (property "Dielectric" "")
    (property "License" "Apache-2.0")
    (property "MPN" "GRM188R60J226MEA0D")
    (property "Manufacturer" "Murata")
    (property "Sheetfile" "dc-dc-conventers.kicad_sch")
    (property "Sheetname" "DC/DC conventers")
    (property "Val" "22u")
    (property "Voltage" "")
    (property "ki_description" " ")
    (attr smd)
    (fp_text reference "C223" (at -1.175 -1.24 -90) (layer "F.SilkS")
        (effects (font (size 0.7 0.7) (thickness 0.15)) (justify left bottom))
    )
    (fp_text value "C_22u_0603" (at 0 1.6 -90) (layer "F.Fab") hide
        (effects (font (size 0.7 0.7) (thickness 0.15)) (justify left bottom))
    )
    (fp_text user "Author: Antmicro" (at -1.682 4.894 -90) (layer "F.Fab") hide
        (effects (font (size 0.7 0.7) (thickness 0.15)) (justify left bottom))
    )
    (fp_text user "License: Apache-2.0" (at -1.682 5.895 -90) (layer "F.Fab") hide
        (effects (font (size 0.7 0.7) (thickness 0.15)) (justify left bottom))
    )
    (fp_text user "${REFERENCE}" (at -1.682 3.895 -90) (layer "F.Fab") hide
        (effects (font (size 0.7 0.7) (thickness 0.15)) (justify left bottom))
    )
    (fp_line (start -0.3 -0.3) (end 0.3 -0.3)
      (stroke (width 0.15) (type solid)) (layer "F.SilkS"))
    (fp_line (start -0.3 0.3) (end 0.3 0.3)
      (stroke (width 0.15) (type solid)) (layer "F.SilkS"))
    (fp_rect (start -1.24 -0.7) (end 1.24 0.7)
      (stroke (width 0.05) (type solid)) (fill none) (layer "F.CrtYd"))
    (fp_rect (start -0.8 -0.4) (end 0.8 0.4)
      (stroke (width 0.15) (type solid)) (fill none) (layer "F.Fab"))
    (pad "1" smd roundrect (at -0.7 0 270) (size 0.6 0.8) (layers "F.Cu" "F.Paste" "F.Mask") (roundrect_rratio 0.2)
      (net 1 "GND") (pintype "passive"))
    (pad "2" smd roundrect (at 0.7 0 270) (size 0.6 0.8) (layers "F.Cu" "F.Paste" "F.Mask") (roundrect_rratio 0.2)
      (net 770 "/Power Supply/DC/DC conventers/PL_3V3_OUT") (pintype "passive"))
  )
	(footprint "kria-k26-devboard-footprints:C_0603_1608Metric" (layer "F.Cu")
    (at 180.775 133.175 -90)
    (descr "Capacitor SMD 0603")
    (tags "capacitor 0603")
    (property "Author" "Antmicro")
    (property "Dielectric" "")
    (property "License" "Apache-2.0")
    (property "MPN" "C1608X5R1E106M080AC")
    (property "Manufacturer" "TDK")
    (property "Sheetfile" "dc-dc-conventers.kicad_sch")
    (property "Sheetname" "DC/DC conventers")
    (property "Val" "10u/25V")
    (property "Voltage" "")
    (property "ki_description" " ")
    (attr smd)
    (fp_text reference "C219" (at -1.025 -0.625 -90) (layer "F.SilkS")
        (effects (font (size 0.7 0.7) (thickness 0.15)) (justify left bottom))
    )
    (fp_text value "C_10u_25V_0603" (at 0 1.6 -90) (layer "F.Fab") hide
        (effects (font (size 0.7 0.7) (thickness 0.15)) (justify left bottom))
    )
    (fp_text user "License: Apache-2.0" (at -1.682 5.895 -90) (layer "F.Fab") hide
        (effects (font (size 0.7 0.7) (thickness 0.15)) (justify left bottom))
    )
    (fp_text user "${REFERENCE}" (at -1.682 3.895 -90) (layer "F.Fab") hide
        (effects (font (size 0.7 0.7) (thickness 0.15)) (justify left bottom))
    )
    (fp_text user "Author: Antmicro" (at -1.682 4.894 -90) (layer "F.Fab") hide
        (effects (font (size 0.7 0.7) (thickness 0.15)) (justify left bottom))
    )
    (fp_line (start -0.3 -0.3) (end 0.3 -0.3)
      (stroke (width 0.15) (type solid)) (layer "F.SilkS"))
    (fp_line (start -0.3 0.3) (end 0.3 0.3)
      (stroke (width 0.15) (type solid)) (layer "F.SilkS"))
    (fp_rect (start -1.24 -0.7) (end 1.24 0.7)
      (stroke (width 0.05) (type solid)) (fill none) (layer "F.CrtYd"))
    (fp_rect (start -0.8 -0.4) (end 0.8 0.4)
      (stroke (width 0.15) (type solid)) (fill none) (layer "F.Fab"))
    (pad "1" smd roundrect (at -0.7 0 270) (size 0.6 0.8) (layers "F.Cu" "F.Paste" "F.Mask") (roundrect_rratio 0.2)
      (net 14 "/Power Supply/DC/DC conventers/DC_MAIN_BUS") (pintype "passive"))
    (pad "2" smd roundrect (at 0.7 0 270) (size 0.6 0.8) (layers "F.Cu" "F.Paste" "F.Mask") (roundrect_rratio 0.2)
      (net 1 "GND") (pintype "passive"))
  )
)
